# S9S_MB_2U (Grand Teton) — schematic netlist excerpt (pin names and nets, part order shuffled) for the footprints in the layout excerpt that follows; sources: Cadence DE-HDL packaged netlist, KiCad conversion of 03242023_DA0F0TMBIJ0_F0T_Motherboard_J_brd_V01_OCP.brd

R4778  Q_RES  1M 1% CHIP  pkg 0402LF  page 307 : A = P12V_AUX_UV_ADR_TRIGGER ; B = FM_UV_ADR_TRIGGER_N_R2
R4772  Q_RES  10K 1% EMPTY  pkg 0402LF  page 307 : A = P3V3_AUX ; B = UV_ADR_P2V5_COMP

(kicad_pcb
	(version 20260206)
	(generator "pcbnew")
	(generator_version "10.0")
	(general
		(thickness 1.6)
		(legacy_teardrops no)
	)
	(paper "A4")
	(title_block
		(title "03242023_DA0F0TMBIJ0_F0T_Motherboard_J_brd_V01_OCP.brd")
		(comment 1 "Grand Teton / footprints 1557-1558 of 6105")
	)
	(layers
		(0 "F.Cu" signal "TOP")
		(4 "In1.Cu" signal "GND")
		(6 "In2.Cu" signal "IN1")
		(8 "In3.Cu" signal "GND1")
		(10 "In4.Cu" signal "IN2")
		(12 "In5.Cu" signal "GND2")
		(14 "In6.Cu" signal "IN3")
		(16 "In7.Cu" signal "GND3")
		(18 "In8.Cu" signal "VCC")
		(20 "In9.Cu" signal "VCC1")
		(22 "In10.Cu" signal "GND4")
		(24 "In11.Cu" signal "IN4")
		(26 "In12.Cu" signal "GND5")
		(28 "In13.Cu" signal "IN5")
		(30 "In14.Cu" signal "GND6")
		(32 "In15.Cu" signal "IN6")
		(34 "In16.Cu" signal "GND7")
		(2 "B.Cu" signal "BOTTOM")
		(9 "F.Adhes" user "F.Adhesive")
		(11 "B.Adhes" user "B.Adhesive")
		(13 "F.Paste" user "Package Geometry/Pastemask Top")
		(15 "B.Paste" user "Package Geometry/Pastemask Bottom")
		(5 "F.SilkS" user "Ref Des/Silkscreen Top")
		(7 "B.SilkS" user "Ref Des/Silkscreen Bottom")
		(1 "F.Mask" user "Board Geometry/Soldermask Top")
		(3 "B.Mask" user "Board Geometry/Soldermask Bottom")
		(17 "Dwgs.User" user "User.Drawings")
		(19 "Cmts.User" user "User.Comments")
		(21 "Eco1.User" user "User.Eco1")
		(23 "Eco2.User" user "User.Eco2")
		(25 "Edge.Cuts" user "Board Geometry/Outline")
		(27 "Margin" user)
		(31 "F.CrtYd" user "Package Geometry/Place Bound Top")
		(29 "B.CrtYd" user "Package Geometry/Place Bound Bottom")
		(35 "F.Fab" user "Ref Des/Assembly Top")
		(33 "B.Fab" user "Ref Des/Assembly Bottom")
	)
	(footprint ""
		(layer "F.Cu")
		(at 205.6384 -97.6884 -90)
		(property "Reference" "R4778"
			(at 0 0 270)
			(layer "F.SilkS")
			(hide yes)
			(effects
				(font
					(size 1.27 1.27)
				)
			)
		)
		(property "Value" ""
			(at 0 0 270)
			(layer "F.Fab")
			(effects
				(font
					(size 1.27 1.27)
				)
			)
		)
		(duplicate_pad_numbers_are_jumpers no)
		(fp_line
			(start -0.7874 0.4064)
			(end -0.7874 -0.4064)
			(stroke
				(width 0.1524)
				(type default)
			)
			(layer "F.SilkS")
		)
		(fp_line
			(start 0.7874 0.4064)
			(end -0.7874 0.4064)
			(stroke
				(width 0.1524)
				(type default)
			)
			(layer "F.SilkS")
		)
		(fp_line
			(start -0.7874 -0.4064)
			(end 0.7874 -0.4064)
			(stroke
				(width 0.1524)
				(type default)
			)
			(layer "F.SilkS")
		)
		(fp_line
			(start 0.7874 -0.4064)
			(end 0.7874 0.4064)
			(stroke
				(width 0.1524)
				(type default)
			)
			(layer "F.SilkS")
		)
		(fp_line
			(start -0.67945 0.3048)
			(end -0.67945 -0.305054)
			(stroke
				(width 0.1)
				(type default)
			)
			(layer "F.Fab")
		)
		(fp_line
			(start -0.12065 0.3048)
			(end -0.67945 0.3048)
			(stroke
				(width 0.1)
				(type default)
			)
			(layer "F.Fab")
		)
		(fp_line
			(start 0.120396 0.3048)
			(end 0.120396 0.2794)
			(stroke
				(width 0.1)
				(type default)
			)
			(layer "F.Fab")
		)
		(fp_line
			(start 0.67945 0.3048)
			(end 0.120396 0.3048)
			(stroke
				(width 0.1)
				(type default)
			)
			(layer "F.Fab")
		)
		(fp_line
			(start -0.12065 0.2794)
			(end -0.12065 0.3048)
			(stroke
				(width 0.1)
				(type default)
			)
			(layer "F.Fab")
		)
		(fp_line
			(start 0.120396 0.2794)
			(end -0.12065 0.2794)
			(stroke
				(width 0.1)
				(type default)
			)
			(layer "F.Fab")
		)
		(fp_line
			(start -0.12065 -0.2794)
			(end 0.12065 -0.2794)
			(stroke
				(width 0.1)
				(type default)
			)
			(layer "F.Fab")
		)
		(fp_line
			(start 0.12065 -0.2794)
			(end 0.12065 -0.3048)
			(stroke
				(width 0.1)
				(type default)
			)
			(layer "F.Fab")
		)
		(fp_line
			(start 0.12065 -0.3048)
			(end 0.67945 -0.3048)
			(stroke
				(width 0.1)
				(type default)
			)
			(layer "F.Fab")
		)
		(fp_line
			(start 0.67945 -0.3048)
			(end 0.67945 0.3048)
			(stroke
				(width 0.1)
				(type default)
			)
			(layer "F.Fab")
		)
		(fp_line
			(start -0.67945 -0.305054)
			(end -0.12065 -0.305054)
			(stroke
				(width 0.1)
				(type default)
			)
			(layer "F.Fab")
		)
		(fp_line
			(start -0.12065 -0.305054)
			(end -0.12065 -0.2794)
			(stroke
				(width 0.1)
				(type default)
			)
			(layer "F.Fab")
		)
		(pad "1" smd circle
			(at -0.40005 0 270)
			(size 0 0)
			(layers "F.Cu" "F.Mask" "F.Paste")
			(net "P12V_AUX_UV_ADR_TRIGGER")
		)
		(pad "2" smd circle
			(at 0.40005 0 270)
			(size 0 0)
			(layers "F.Cu" "F.Mask" "F.Paste")
			(net "FM_UV_ADR_TRIGGER_N_R2")
		)
	)
	(footprint ""
		(layer "F.Cu")
		(at 202.7936 -92.6338 90)
		(property "Reference" "R4772"
			(at 0 0 90)
			(layer "F.SilkS")
			(hide yes)
			(effects
				(font
					(size 1.27 1.27)
				)
			)
		)
		(property "Value" ""
			(at 0 0 90)
			(layer "F.Fab")
			(effects
				(font
					(size 1.27 1.27)
				)
			)
		)
		(duplicate_pad_numbers_are_jumpers no)
		(fp_line
			(start 0.7874 -0.4064)
			(end 0.7874 0.4064)
			(stroke
				(width 0.1524)
				(type default)
			)
			(layer "F.SilkS")
		)
		(fp_line
			(start -0.7874 -0.4064)
			(end 0.7874 -0.4064)
			(stroke
				(width 0.1524)
				(type default)
			)
			(layer "F.SilkS")
		)
		(fp_line
			(start 0.7874 0.4064)
			(end -0.7874 0.4064)
			(stroke
				(width 0.1524)
				(type default)
			)
			(layer "F.SilkS")
		)
		(fp_line
			(start -0.7874 0.4064)
			(end -0.7874 -0.4064)
			(stroke
				(width 0.1524)
				(type default)
			)
			(layer "F.SilkS")
		)
		(fp_line
			(start -0.12065 -0.305054)
			(end -0.12065 -0.2794)
			(stroke
				(width 0.1)
				(type default)
			)
			(layer "F.Fab")
		)
		(fp_line
			(start -0.67945 -0.305054)
			(end -0.12065 -0.305054)
			(stroke
				(width 0.1)
				(type default)
			)
			(layer "F.Fab")
		)
		(fp_line
			(start 0.67945 -0.3048)
			(end 0.67945 0.3048)
			(stroke
				(width 0.1)
				(type default)
			)
			(layer "F.Fab")
		)
		(fp_line
			(start 0.12065 -0.3048)
			(end 0.67945 -0.3048)
			(stroke
				(width 0.1)
				(type default)
			)
			(layer "F.Fab")
		)
		(fp_line
			(start 0.12065 -0.2794)
			(end 0.12065 -0.3048)
			(stroke
				(width 0.1)
				(type default)
			)
			(layer "F.Fab")
		)
		(fp_line
			(start -0.12065 -0.2794)
			(end 0.12065 -0.2794)
			(stroke
				(width 0.1)
				(type default)
			)
			(layer "F.Fab")
		)
		(fp_line
			(start 0.120396 0.2794)
			(end -0.12065 0.2794)
			(stroke
				(width 0.1)
				(type default)
			)
			(layer "F.Fab")
		)
		(fp_line
			(start -0.12065 0.2794)
			(end -0.12065 0.3048)
			(stroke
				(width 0.1)
				(type default)
			)
			(layer "F.Fab")
		)
		(fp_line
			(start 0.67945 0.3048)
			(end 0.120396 0.3048)
			(stroke
				(width 0.1)
				(type default)
			)
			(layer "F.Fab")
		)
		(fp_line
			(start 0.120396 0.3048)
			(end 0.120396 0.2794)
			(stroke
				(width 0.1)
				(type default)
			)
			(layer "F.Fab")
		)
		(fp_line
			(start -0.12065 0.3048)
			(end -0.67945 0.3048)
			(stroke
				(width 0.1)
				(type default)
			)
			(layer "F.Fab")
		)
		(fp_line
			(start -0.67945 0.3048)
			(end -0.67945 -0.305054)
			(stroke
				(width 0.1)
				(type default)
			)
			(layer "F.Fab")
		)
		(pad "1" smd circle
			(at -0.40005 0 90)
			(size 0 0)
			(layers "F.Cu" "F.Mask" "F.Paste")
			(net "P3V3_AUX")
		)
		(pad "2" smd circle
			(at 0.40005 0 90)
			(size 0 0)
			(layers "F.Cu" "F.Mask" "F.Paste")
			(net "UV_ADR_P2V5_COMP")
		)
	)
)
